# BASEBOARD_FAB2 (Tioga Pass) — schematic netlist excerpt (pin names and nets, part order shuffled) for the footprints in the layout excerpt that follows; sources: Cadence DE-HDL packaged netlist, KiCad conversion of Wiwynn_Tioga_Pass_MB.brd

C3A8  CAP  10UF 4V 20% X6S  pkg 0603LF  page 234 : A = PVPP_KLM ; B = GND
L4C2  IND-300NH-20-GP  pkg DISCRET-GB1  page 205 : S = VR_PVSA_CPU0_PHASE_SW ; F = PVSA_CPU0
C5G6  CAP_A  47UF 4V 20% X5R  pkg 0603V  page 217 : A = PVDDQ_ABC ; B = GND

(kicad_pcb
	(version 20260206)
	(generator "pcbnew")
	(generator_version "10.0")
	(general
		(thickness 1.6)
		(legacy_teardrops no)
	)
	(paper "A4")
	(title_block
		(title "Wiwynn_Tioga_Pass_MB.brd")
		(comment 1 "Tioga Pass / footprints 1890-1892 of 4770")
	)
	(layers
		(0 "F.Cu" signal "TOP")
		(4 "In1.Cu" signal "L2GND")
		(6 "In2.Cu" signal "L3")
		(8 "In3.Cu" signal "L4GND")
		(10 "In4.Cu" signal "L5")
		(12 "In5.Cu" signal "L6GND")
		(14 "In6.Cu" signal "L7VCC")
		(16 "In7.Cu" signal "L8VCC")
		(18 "In8.Cu" signal "L9GND")
		(20 "In9.Cu" signal "L10")
		(22 "In10.Cu" signal "L11GND")
		(24 "In11.Cu" signal "L12")
		(26 "In12.Cu" signal "L13GND")
		(2 "B.Cu" signal "BOTTOM")
		(9 "F.Adhes" user "F.Adhesive")
		(11 "B.Adhes" user "B.Adhesive")
		(13 "F.Paste" user "Package Geometry/Pastemask Top")
		(15 "B.Paste" user "Package Geometry/Pastemask Bottom")
		(5 "F.SilkS" user "Ref Des/Silkscreen Top")
		(7 "B.SilkS" user "Ref Des/Silkscreen Bottom")
		(1 "F.Mask" user "Board Geometry/Soldermask Top")
		(3 "B.Mask" user "Board Geometry/Soldermask Bottom")
		(17 "Dwgs.User" user "User.Drawings")
		(19 "Cmts.User" user "User.Comments")
		(21 "Eco1.User" user "User.Eco1")
		(23 "Eco2.User" user "User.Eco2")
		(25 "Edge.Cuts" user "Board Geometry/Outline")
		(27 "Margin" user)
		(31 "F.CrtYd" user "Package Geometry/Place Bound Top")
		(29 "B.CrtYd" user "Package Geometry/Place Bound Bottom")
		(35 "F.Fab" user "Ref Des/Assembly Top")
		(33 "B.Fab" user "Ref Des/Assembly Bottom")
	)
	(footprint ""
		(layer "F.Cu")
		(at 205.025498 -97.454974)
		(property "Reference" "L4C2"
			(at 3.378708 -4.251706 0)
			(unlocked yes)
			(layer "F.SilkS")
			(effects
				(font
					(size 0.4064 0.254)
					(thickness 0.1524)
				)
			)
		)
		(property "Value" ""
			(at 0 0 0)
			(layer "F.Fab")
			(effects
				(font
					(size 1.27 1.27)
				)
			)
		)
		(duplicate_pad_numbers_are_jumpers no)
		(fp_line
			(start -1.1303 -3.199892)
			(end 8.3693 -3.199892)
			(stroke
				(width 0.1524)
				(type default)
			)
			(layer "F.SilkS")
		)
		(fp_line
			(start -1.1303 -1.6637)
			(end -1.1303 -3.199892)
			(stroke
				(width 0.1524)
				(type default)
			)
			(layer "F.SilkS")
		)
		(fp_line
			(start -1.1303 3.199892)
			(end -1.1303 1.6637)
			(stroke
				(width 0.1524)
				(type default)
			)
			(layer "F.SilkS")
		)
		(fp_line
			(start 8.3693 -3.199892)
			(end 8.3693 -1.6637)
			(stroke
				(width 0.1524)
				(type default)
			)
			(layer "F.SilkS")
		)
		(fp_line
			(start 8.3693 1.6637)
			(end 8.3693 3.199892)
			(stroke
				(width 0.1524)
				(type default)
			)
			(layer "F.SilkS")
		)
		(fp_line
			(start 8.3693 3.199892)
			(end -1.1303 3.199892)
			(stroke
				(width 0.1524)
				(type default)
			)
			(layer "F.SilkS")
		)
		(fp_rect
			(start -1.1303 3.199892)
			(end 8.3693 -3.199892)
			(stroke
				(width 0)
				(type default)
			)
			(fill no)
			(layer "F.CrtYd")
		)
		(fp_line
			(start -1.1303 -3.199892)
			(end 8.3693 -3.199892)
			(stroke
				(width 0.1)
				(type default)
			)
			(layer "F.Fab")
		)
		(fp_line
			(start -1.1303 3.199892)
			(end -1.1303 -3.199892)
			(stroke
				(width 0.1)
				(type default)
			)
			(layer "F.Fab")
		)
		(fp_line
			(start 8.3693 -3.199892)
			(end 8.3693 3.199892)
			(stroke
				(width 0.1)
				(type default)
			)
			(layer "F.Fab")
		)
		(fp_line
			(start 8.3693 3.199892)
			(end -1.1303 3.199892)
			(stroke
				(width 0.1)
				(type default)
			)
			(layer "F.Fab")
		)
		(pad "1" smd rect
			(at 0 0)
			(size 3.683 2.667)
			(layers "F.Cu" "F.Mask" "F.Paste")
			(net "VR_PVSA_CPU0_PHASE_SW")
		)
		(pad "2" smd rect
			(at 7.239 0)
			(size 3.683 2.667)
			(layers "F.Cu" "F.Mask" "F.Paste")
			(net "PVSA_CPU0")
		)
	)
	(footprint ""
		(layer "F.Cu")
		(at 269.559532 -12.954 90)
		(property "Reference" "C5G6"
			(at 1.848866 0.752348 90)
			(unlocked yes)
			(layer "F.SilkS")
			(effects
				(font
					(size 1.27 0.9652)
					(thickness 0.1524)
				)
			)
		)
		(property "Value" ""
			(at 0 0 90)
			(layer "F.Fab")
			(effects
				(font
					(size 1.27 1.27)
				)
			)
		)
		(duplicate_pad_numbers_are_jumpers no)
		(fp_rect
			(start -0.500126 1.598422)
			(end 0.500126 -0.201422)
			(stroke
				(width 0)
				(type default)
			)
			(fill no)
			(layer "F.CrtYd")
		)
		(fp_line
			(start 0.500126 -0.201422)
			(end 0.500126 1.598422)
			(stroke
				(width 0.1)
				(type default)
			)
			(layer "F.Fab")
		)
		(fp_line
			(start -0.500126 -0.201422)
			(end 0.500126 -0.201422)
			(stroke
				(width 0.1)
				(type default)
			)
			(layer "F.Fab")
		)
		(fp_line
			(start 0.500126 1.598422)
			(end -0.500126 1.598422)
			(stroke
				(width 0.1)
				(type default)
			)
			(layer "F.Fab")
		)
		(fp_line
			(start -0.500126 1.598422)
			(end -0.500126 -0.201422)
			(stroke
				(width 0.1)
				(type default)
			)
			(layer "F.Fab")
		)
		(pad "1" smd rect
			(at 0 0)
			(size 0.889 0.9906)
			(layers "F.Cu" "F.Mask" "F.Paste")
			(net "PVDDQ_ABC")
		)
		(pad "2" smd rect
			(at 0 1.397)
			(size 0.889 0.9906)
			(layers "F.Cu" "F.Mask" "F.Paste")
			(net "GND")
		)
		(zone
			(layer "F.Cu")
			(hatch none 0.5)
			(connect_pads
				(clearance 0)
			)
			(min_thickness 0.25)
			(keepout
				(tracks not_allowed)
				(vias allowed)
				(pads allowed)
				(copperpour not_allowed)
				(footprints allowed)
			)
			(placement
				(enabled no)
				(sheetname "")
			)
			(fill
				(thermal_gap 0.5)
				(thermal_bridge_width 0.5)
				(island_removal_mode 0)
			)
			(polygon
				(pts
					(xy 270.512032 -12.4587) (xy 270.512032 -13.4493) (xy 270.004032 -13.4493) (xy 270.004032 -12.4587)
				)
			)
		)
		(zone
			(layer "F.Cu")
			(hatch none 0.5)
			(connect_pads
				(clearance 0)
			)
			(min_thickness 0.25)
			(keepout
				(tracks allowed)
				(vias not_allowed)
				(pads allowed)
				(copperpour not_allowed)
				(footprints allowed)
			)
			(placement
				(enabled no)
				(sheetname "")
			)
			(fill
				(thermal_gap 0.5)
				(thermal_bridge_width 0.5)
				(island_removal_mode 0)
			)
			(polygon
				(pts
					(xy 270.512032 -12.4587) (xy 270.512032 -13.4493) (xy 270.004032 -13.4493) (xy 270.004032 -12.4587)
				)
			)
		)
	)
	(footprint ""
		(layer "F.Cu")
		(at 155.702 -140.0048 90)
		(property "Reference" "C3A8"
			(at 0 0 90)
			(layer "F.SilkS")
			(hide yes)
			(effects
				(font
					(size 1.27 1.27)
				)
			)
		)
		(property "Value" ""
			(at 0 0 90)
			(layer "F.Fab")
			(effects
				(font
					(size 1.27 1.27)
				)
			)
		)
		(duplicate_pad_numbers_are_jumpers no)
		(fp_rect
			(start -0.4953 1.6002)
			(end 0.4953 -0.2032)
			(stroke
				(width 0)
				(type default)
			)
			(fill no)
			(layer "F.CrtYd")
		)
		(fp_line
			(start 0.4953 -0.2032)
			(end 0.4953 1.6002)
			(stroke
				(width 0.1)
				(type default)
			)
			(layer "F.Fab")
		)
		(fp_line
			(start -0.4953 -0.2032)
			(end 0.4953 -0.2032)
			(stroke
				(width 0.1)
				(type default)
			)
			(layer "F.Fab")
		)
		(fp_line
			(start 0.4953 1.6002)
			(end -0.4953 1.6002)
			(stroke
				(width 0.1)
				(type default)
			)
			(layer "F.Fab")
		)
		(fp_line
			(start -0.4953 1.6002)
			(end -0.4953 -0.2032)
			(stroke
				(width 0.1)
				(type default)
			)
			(layer "F.Fab")
		)
		(pad "1" smd rect
			(at 0 0 90)
			(size 0.762 0.889)
			(layers "F.Cu" "F.Mask" "F.Paste")
			(net "PVPP_KLM")
		)
		(pad "2" smd rect
			(at 0 1.397 90)
			(size 0.762 0.889)
			(layers "F.Cu" "F.Mask" "F.Paste")
			(net "GND")
		)
		(zone
			(layer "F.Cu")
			(hatch none 0.5)
			(connect_pads
				(clearance 0)
			)
			(min_thickness 0.25)
			(keepout
				(tracks not_allowed)
				(vias allowed)
				(pads allowed)
				(copperpour not_allowed)
				(footprints allowed)
			)
			(placement
				(enabled no)
				(sheetname "")
			)
			(fill
				(thermal_gap 0.5)
				(thermal_bridge_width 0.5)
				(island_removal_mode 0)
			)
			(polygon
				(pts
					(xy 156.6545 -139.6238) (xy 156.6545 -140.3858) (xy 156.1465 -140.3858) (xy 156.1465 -139.6238)
				)
			)
		)
	)
)
